(kicad_pcb
	(version 20260206)
	(generator "pcbnew")
	(generator_version "10.0")
	(general
		(thickness 1.6)
		(legacy_teardrops no)
	)
	(paper "A4")
	(title_block
		(title "12092022_DA0F0TMDCD0_F0T_Management_Board_D_brd_V3_OCP.brd")
		(comment 1 "Grand Teton / footprints 696-701 of 1440")
	)
	(layers
		(0 "F.Cu" signal "TOP")
		(4 "In1.Cu" signal "GND")
		(6 "In2.Cu" signal "IN1")
		(8 "In3.Cu" signal "GND1")
		(10 "In4.Cu" signal "IN2")
		(12 "In5.Cu" signal "VCC")
		(14 "In6.Cu" signal "VCC1")
		(16 "In7.Cu" signal "IN3")
		(18 "In8.Cu" signal "GND2")
		(20 "In9.Cu" signal "IN4")
		(22 "In10.Cu" signal "GND3")
		(2 "B.Cu" signal "BOTTOM")
		(9 "F.Adhes" user "F.Adhesive")
		(11 "B.Adhes" user "B.Adhesive")
		(13 "F.Paste" user "Package Geometry/Pastemask Top")
		(15 "B.Paste" user "Package Geometry/Pastemask Bottom")
		(5 "F.SilkS" user "Ref Des/Silkscreen Top")
		(7 "B.SilkS" user "Ref Des/Silkscreen Bottom")
		(1 "F.Mask" user "Board Geometry/Soldermask Top")
		(3 "B.Mask" user "Board Geometry/Soldermask Bottom")
		(17 "Dwgs.User" user "User.Drawings")
		(19 "Cmts.User" user "User.Comments")
		(21 "Eco1.User" user "User.Eco1")
		(23 "Eco2.User" user "User.Eco2")
		(25 "Edge.Cuts" user "Board Geometry/Outline")
		(27 "Margin" user)
		(31 "F.CrtYd" user "Package Geometry/Place Bound Top")
		(29 "B.CrtYd" user "Package Geometry/Place Bound Bottom")
		(35 "F.Fab" user "Ref Des/Assembly Top")
		(33 "B.Fab" user "Ref Des/Assembly Bottom")
	)
	(footprint ""
		(layer "F.Cu")
		(at 21.168614 -25.111202 -90)
		(property "Reference" "PL33"
			(at 0 0 270)
			(layer "F.SilkS")
			(hide yes)
			(effects
				(font
					(size 1.27 1.27)
				)
			)
		)
		(property "Value" ""
			(at 0 0 270)
			(layer "F.Fab")
			(effects
				(font
					(size 1.27 1.27)
				)
			)
		)
		(duplicate_pad_numbers_are_jumpers no)
		(fp_line
			(start -3.64998 3.350006)
			(end -3.64998 1.8288)
			(stroke
				(width 0.1524)
				(type default)
			)
			(layer "F.SilkS")
		)
		(fp_line
			(start 3.64998 3.350006)
			(end -3.64998 3.350006)
			(stroke
				(width 0.1524)
				(type default)
			)
			(layer "F.SilkS")
		)
		(fp_line
			(start 3.64998 1.8034)
			(end 3.64998 3.350006)
			(stroke
				(width 0.1524)
				(type default)
			)
			(layer "F.SilkS")
		)
		(fp_line
			(start -3.64998 -1.8034)
			(end -3.64998 -3.350006)
			(stroke
				(width 0.1524)
				(type default)
			)
			(layer "F.SilkS")
		)
		(fp_line
			(start -3.6576 -3.350006)
			(end 3.64998 -3.350006)
			(stroke
				(width 0.1524)
				(type default)
			)
			(layer "F.SilkS")
		)
		(fp_line
			(start 3.64998 -3.350006)
			(end 3.64998 -1.8034)
			(stroke
				(width 0.1524)
				(type default)
			)
			(layer "F.SilkS")
		)
		(fp_line
			(start -3.64998 3.350006)
			(end -3.64998 -3.350006)
			(stroke
				(width 0.1)
				(type default)
			)
			(layer "F.Fab")
		)
		(fp_line
			(start 3.64998 3.350006)
			(end -3.64998 3.350006)
			(stroke
				(width 0.1)
				(type default)
			)
			(layer "F.Fab")
		)
		(fp_line
			(start -3.64998 -3.350006)
			(end 3.64998 -3.350006)
			(stroke
				(width 0.1)
				(type default)
			)
			(layer "F.Fab")
		)
		(fp_line
			(start 3.64998 -3.350006)
			(end 3.64998 3.350006)
			(stroke
				(width 0.1)
				(type default)
			)
			(layer "F.Fab")
		)
		(pad "1" smd rect
			(at -2.92481 0 270)
			(size 2.15392 3.302)
			(layers "F.Cu" "F.Mask" "F.Paste")
			(net "SW_P1V0_AUX_SW")
		)
		(pad "2" smd rect
			(at 2.92481 0 270)
			(size 2.15392 3.302)
			(layers "F.Cu" "F.Mask" "F.Paste")
			(net "P1V0_AUX")
		)
	)
	(footprint ""
		(layer "F.Cu")
		(at 53.594 -10.795 90)
		(property "Reference" "R107"
			(at 0 0 90)
			(layer "F.SilkS")
			(hide yes)
			(effects
				(font
					(size 1.27 1.27)
				)
			)
		)
		(property "Value" ""
			(at 0 0 90)
			(layer "F.Fab")
			(effects
				(font
					(size 1.27 1.27)
				)
			)
		)
		(duplicate_pad_numbers_are_jumpers no)
		(fp_line
			(start 0.7874 -0.4064)
			(end 0.7874 0.4064)
			(stroke
				(width 0.1524)
				(type default)
			)
			(layer "F.SilkS")
		)
		(fp_line
			(start -0.7874 -0.4064)
			(end 0.7874 -0.4064)
			(stroke
				(width 0.1524)
				(type default)
			)
			(layer "F.SilkS")
		)
		(fp_line
			(start 0.7874 0.4064)
			(end -0.7874 0.4064)
			(stroke
				(width 0.1524)
				(type default)
			)
			(layer "F.SilkS")
		)
		(fp_line
			(start -0.7874 0.4064)
			(end -0.7874 -0.4064)
			(stroke
				(width 0.1524)
				(type default)
			)
			(layer "F.SilkS")
		)
		(fp_line
			(start -0.12065 -0.305054)
			(end -0.12065 -0.2794)
			(stroke
				(width 0.1)
				(type default)
			)
			(layer "F.Fab")
		)
		(fp_line
			(start -0.67945 -0.305054)
			(end -0.12065 -0.305054)
			(stroke
				(width 0.1)
				(type default)
			)
			(layer "F.Fab")
		)
		(fp_line
			(start 0.67945 -0.3048)
			(end 0.67945 0.3048)
			(stroke
				(width 0.1)
				(type default)
			)
			(layer "F.Fab")
		)
		(fp_line
			(start 0.12065 -0.3048)
			(end 0.67945 -0.3048)
			(stroke
				(width 0.1)
				(type default)
			)
			(layer "F.Fab")
		)
		(fp_line
			(start 0.12065 -0.2794)
			(end 0.12065 -0.3048)
			(stroke
				(width 0.1)
				(type default)
			)
			(layer "F.Fab")
		)
		(fp_line
			(start -0.12065 -0.2794)
			(end 0.12065 -0.2794)
			(stroke
				(width 0.1)
				(type default)
			)
			(layer "F.Fab")
		)
		(fp_line
			(start 0.120396 0.2794)
			(end -0.12065 0.2794)
			(stroke
				(width 0.1)
				(type default)
			)
			(layer "F.Fab")
		)
		(fp_line
			(start -0.12065 0.2794)
			(end -0.12065 0.3048)
			(stroke
				(width 0.1)
				(type default)
			)
			(layer "F.Fab")
		)
		(fp_line
			(start 0.67945 0.3048)
			(end 0.120396 0.3048)
			(stroke
				(width 0.1)
				(type default)
			)
			(layer "F.Fab")
		)
		(fp_line
			(start 0.120396 0.3048)
			(end 0.120396 0.2794)
			(stroke
				(width 0.1)
				(type default)
			)
			(layer "F.Fab")
		)
		(fp_line
			(start -0.12065 0.3048)
			(end -0.67945 0.3048)
			(stroke
				(width 0.1)
				(type default)
			)
			(layer "F.Fab")
		)
		(fp_line
			(start -0.67945 0.3048)
			(end -0.67945 -0.305054)
			(stroke
				(width 0.1)
				(type default)
			)
			(layer "F.Fab")
		)
		(pad "1" smd circle
			(at -0.40005 0 90)
			(size 0 0)
			(layers "F.Cu" "F.Mask" "F.Paste")
			(net "LED_D21_R3")
		)
		(pad "2" smd circle
			(at 0.40005 0 90)
			(size 0 0)
			(layers "F.Cu" "F.Mask" "F.Paste")
			(net "LED_D21_R2")
		)
	)
	(footprint ""
		(layer "F.Cu")
		(at 29.27604 -70.536054 90)
		(property "Reference" "R650"
			(at 0 0 90)
			(layer "F.SilkS")
			(hide yes)
			(effects
				(font
					(size 1.27 1.27)
				)
			)
		)
		(property "Value" ""
			(at 0 0 90)
			(layer "F.Fab")
			(effects
				(font
					(size 1.27 1.27)
				)
			)
		)
		(duplicate_pad_numbers_are_jumpers no)
		(fp_line
			(start 0.7874 -0.4064)
			(end 0.7874 0.4064)
			(stroke
				(width 0.1524)
				(type default)
			)
			(layer "F.SilkS")
		)
		(fp_line
			(start -0.7874 -0.4064)
			(end 0.7874 -0.4064)
			(stroke
				(width 0.1524)
				(type default)
			)
			(layer "F.SilkS")
		)
		(fp_line
			(start 0.7874 0.4064)
			(end -0.7874 0.4064)
			(stroke
				(width 0.1524)
				(type default)
			)
			(layer "F.SilkS")
		)
		(fp_line
			(start -0.7874 0.4064)
			(end -0.7874 -0.4064)
			(stroke
				(width 0.1524)
				(type default)
			)
			(layer "F.SilkS")
		)
		(fp_line
			(start -0.12065 -0.305054)
			(end -0.12065 -0.2794)
			(stroke
				(width 0.1)
				(type default)
			)
			(layer "F.Fab")
		)
		(fp_line
			(start -0.67945 -0.305054)
			(end -0.12065 -0.305054)
			(stroke
				(width 0.1)
				(type default)
			)
			(layer "F.Fab")
		)
		(fp_line
			(start 0.67945 -0.3048)
			(end 0.67945 0.3048)
			(stroke
				(width 0.1)
				(type default)
			)
			(layer "F.Fab")
		)
		(fp_line
			(start 0.12065 -0.3048)
			(end 0.67945 -0.3048)
			(stroke
				(width 0.1)
				(type default)
			)
			(layer "F.Fab")
		)
		(fp_line
			(start 0.12065 -0.2794)
			(end 0.12065 -0.3048)
			(stroke
				(width 0.1)
				(type default)
			)
			(layer "F.Fab")
		)
		(fp_line
			(start -0.12065 -0.2794)
			(end 0.12065 -0.2794)
			(stroke
				(width 0.1)
				(type default)
			)
			(layer "F.Fab")
		)
		(fp_line
			(start 0.120396 0.2794)
			(end -0.12065 0.2794)
			(stroke
				(width 0.1)
				(type default)
			)
			(layer "F.Fab")
		)
		(fp_line
			(start -0.12065 0.2794)
			(end -0.12065 0.3048)
			(stroke
				(width 0.1)
				(type default)
			)
			(layer "F.Fab")
		)
		(fp_line
			(start 0.67945 0.3048)
			(end 0.120396 0.3048)
			(stroke
				(width 0.1)
				(type default)
			)
			(layer "F.Fab")
		)
		(fp_line
			(start 0.120396 0.3048)
			(end 0.120396 0.2794)
			(stroke
				(width 0.1)
				(type default)
			)
			(layer "F.Fab")
		)
		(fp_line
			(start -0.12065 0.3048)
			(end -0.67945 0.3048)
			(stroke
				(width 0.1)
				(type default)
			)
			(layer "F.Fab")
		)
		(fp_line
			(start -0.67945 0.3048)
			(end -0.67945 -0.305054)
			(stroke
				(width 0.1)
				(type default)
			)
			(layer "F.Fab")
		)
		(pad "1" smd circle
			(at -0.40005 0 90)
			(size 0 0)
			(layers "F.Cu" "F.Mask" "F.Paste")
			(net "BMC_EMMC_DT7")
		)
		(pad "2" smd circle
			(at 0.40005 0 90)
			(size 0 0)
			(layers "F.Cu" "F.Mask" "F.Paste")
			(net "EMMC_DT7_R")
		)
	)
	(footprint ""
		(layer "F.Cu")
		(at 52.6542 -109.3978 -90)
		(property "Reference" "R863"
			(at 0 0 270)
			(layer "F.SilkS")
			(hide yes)
			(effects
				(font
					(size 1.27 1.27)
				)
			)
		)
		(property "Value" ""
			(at 0 0 270)
			(layer "F.Fab")
			(effects
				(font
					(size 1.27 1.27)
				)
			)
		)
		(duplicate_pad_numbers_are_jumpers no)
		(fp_line
			(start -0.7874 0.4064)
			(end -0.7874 -0.4064)
			(stroke
				(width 0.1524)
				(type default)
			)
			(layer "F.SilkS")
		)
		(fp_line
			(start 0.7874 0.4064)
			(end -0.7874 0.4064)
			(stroke
				(width 0.1524)
				(type default)
			)
			(layer "F.SilkS")
		)
		(fp_line
			(start -0.7874 -0.4064)
			(end 0.7874 -0.4064)
			(stroke
				(width 0.1524)
				(type default)
			)
			(layer "F.SilkS")
		)
		(fp_line
			(start 0.7874 -0.4064)
			(end 0.7874 0.4064)
			(stroke
				(width 0.1524)
				(type default)
			)
			(layer "F.SilkS")
		)
		(fp_line
			(start -0.67945 0.3048)
			(end -0.67945 -0.305054)
			(stroke
				(width 0.1)
				(type default)
			)
			(layer "F.Fab")
		)
		(fp_line
			(start -0.12065 0.3048)
			(end -0.67945 0.3048)
			(stroke
				(width 0.1)
				(type default)
			)
			(layer "F.Fab")
		)
		(fp_line
			(start 0.120396 0.3048)
			(end 0.120396 0.2794)
			(stroke
				(width 0.1)
				(type default)
			)
			(layer "F.Fab")
		)
		(fp_line
			(start 0.67945 0.3048)
			(end 0.120396 0.3048)
			(stroke
				(width 0.1)
				(type default)
			)
			(layer "F.Fab")
		)
		(fp_line
			(start -0.12065 0.2794)
			(end -0.12065 0.3048)
			(stroke
				(width 0.1)
				(type default)
			)
			(layer "F.Fab")
		)
		(fp_line
			(start 0.120396 0.2794)
			(end -0.12065 0.2794)
			(stroke
				(width 0.1)
				(type default)
			)
			(layer "F.Fab")
		)
		(fp_line
			(start -0.12065 -0.2794)
			(end 0.12065 -0.2794)
			(stroke
				(width 0.1)
				(type default)
			)
			(layer "F.Fab")
		)
		(fp_line
			(start 0.12065 -0.2794)
			(end 0.12065 -0.3048)
			(stroke
				(width 0.1)
				(type default)
			)
			(layer "F.Fab")
		)
		(fp_line
			(start 0.12065 -0.3048)
			(end 0.67945 -0.3048)
			(stroke
				(width 0.1)
				(type default)
			)
			(layer "F.Fab")
		)
		(fp_line
			(start 0.67945 -0.3048)
			(end 0.67945 0.3048)
			(stroke
				(width 0.1)
				(type default)
			)
			(layer "F.Fab")
		)
		(fp_line
			(start -0.67945 -0.305054)
			(end -0.12065 -0.305054)
			(stroke
				(width 0.1)
				(type default)
			)
			(layer "F.Fab")
		)
		(fp_line
			(start -0.12065 -0.305054)
			(end -0.12065 -0.2794)
			(stroke
				(width 0.1)
				(type default)
			)
			(layer "F.Fab")
		)
		(pad "1" smd circle
			(at -0.40005 0 270)
			(size 0 0)
			(layers "F.Cu" "F.Mask" "F.Paste")
			(net "SPI_SYS_HOLD_R_IO3")
		)
		(pad "2" smd circle
			(at 0.40005 0 270)
			(size 0 0)
			(layers "F.Cu" "F.Mask" "F.Paste")
			(net "SPI_SYS_MUX_HOLD_IO3")
		)
	)
	(footprint ""
		(layer "F.Cu")
		(at 41.916604 -87.679784 -90)
		(property "Reference" "R487"
			(at 0 0 270)
			(layer "F.SilkS")
			(hide yes)
			(effects
				(font
					(size 1.27 1.27)
				)
			)
		)
		(property "Value" ""
			(at 0 0 270)
			(layer "F.Fab")
			(effects
				(font
					(size 1.27 1.27)
				)
			)
		)
		(duplicate_pad_numbers_are_jumpers no)
		(fp_line
			(start -0.7874 0.4064)
			(end -0.7874 -0.4064)
			(stroke
				(width 0.1524)
				(type default)
			)
			(layer "F.SilkS")
		)
		(fp_line
			(start 0.7874 0.4064)
			(end -0.7874 0.4064)
			(stroke
				(width 0.1524)
				(type default)
			)
			(layer "F.SilkS")
		)
		(fp_line
			(start -0.7874 -0.4064)
			(end 0.7874 -0.4064)
			(stroke
				(width 0.1524)
				(type default)
			)
			(layer "F.SilkS")
		)
		(fp_line
			(start 0.7874 -0.4064)
			(end 0.7874 0.4064)
			(stroke
				(width 0.1524)
				(type default)
			)
			(layer "F.SilkS")
		)
		(fp_line
			(start -0.67945 0.3048)
			(end -0.67945 -0.305054)
			(stroke
				(width 0.1)
				(type default)
			)
			(layer "F.Fab")
		)
		(fp_line
			(start -0.12065 0.3048)
			(end -0.67945 0.3048)
			(stroke
				(width 0.1)
				(type default)
			)
			(layer "F.Fab")
		)
		(fp_line
			(start 0.120396 0.3048)
			(end 0.120396 0.2794)
			(stroke
				(width 0.1)
				(type default)
			)
			(layer "F.Fab")
		)
		(fp_line
			(start 0.67945 0.3048)
			(end 0.120396 0.3048)
			(stroke
				(width 0.1)
				(type default)
			)
			(layer "F.Fab")
		)
		(fp_line
			(start -0.12065 0.2794)
			(end -0.12065 0.3048)
			(stroke
				(width 0.1)
				(type default)
			)
			(layer "F.Fab")
		)
		(fp_line
			(start 0.120396 0.2794)
			(end -0.12065 0.2794)
			(stroke
				(width 0.1)
				(type default)
			)
			(layer "F.Fab")
		)
		(fp_line
			(start -0.12065 -0.2794)
			(end 0.12065 -0.2794)
			(stroke
				(width 0.1)
				(type default)
			)
			(layer "F.Fab")
		)
		(fp_line
			(start 0.12065 -0.2794)
			(end 0.12065 -0.3048)
			(stroke
				(width 0.1)
				(type default)
			)
			(layer "F.Fab")
		)
		(fp_line
			(start 0.12065 -0.3048)
			(end 0.67945 -0.3048)
			(stroke
				(width 0.1)
				(type default)
			)
			(layer "F.Fab")
		)
		(fp_line
			(start 0.67945 -0.3048)
			(end 0.67945 0.3048)
			(stroke
				(width 0.1)
				(type default)
			)
			(layer "F.Fab")
		)
		(fp_line
			(start -0.67945 -0.305054)
			(end -0.12065 -0.305054)
			(stroke
				(width 0.1)
				(type default)
			)
			(layer "F.Fab")
		)
		(fp_line
			(start -0.12065 -0.305054)
			(end -0.12065 -0.2794)
			(stroke
				(width 0.1)
				(type default)
			)
			(layer "F.Fab")
		)
		(pad "1" smd circle
			(at -0.40005 0 270)
			(size 0 0)
			(layers "F.Cu" "F.Mask" "F.Paste")
			(net "SPI_PCH_CS0_FLASH_R1_N")
		)
		(pad "2" smd circle
			(at 0.40005 0 270)
			(size 0 0)
			(layers "F.Cu" "F.Mask" "F.Paste")
			(net "GND")
		)
	)
	(footprint ""
		(layer "F.Cu")
		(at 48.4378 -79.0194 180)
		(property "Reference" "C313"
			(at 0 0 180)
			(layer "F.SilkS")
			(hide yes)
			(effects
				(font
					(size 1.27 1.27)
				)
			)
		)
		(property "Value" ""
			(at 0 0 180)
			(layer "F.Fab")
			(effects
				(font
					(size 1.27 1.27)
				)
			)
		)
		(duplicate_pad_numbers_are_jumpers no)
		(fp_line
			(start 0.7874 0.4064)
			(end -0.7874 0.4064)
			(stroke
				(width 0.1524)
				(type default)
			)
			(layer "F.SilkS")
		)
		(fp_line
			(start 0.7874 -0.4064)
			(end 0.7874 0.4064)
			(stroke
				(width 0.1524)
				(type default)
			)
			(layer "F.SilkS")
		)
		(fp_line
			(start -0.7874 0.4064)
			(end -0.7874 -0.4064)
			(stroke
				(width 0.1524)
				(type default)
			)
			(layer "F.SilkS")
		)
		(fp_line
			(start -0.7874 -0.4064)
			(end 0.7874 -0.4064)
			(stroke
				(width 0.1524)
				(type default)
			)
			(layer "F.SilkS")
		)
		(fp_line
			(start 0.67945 0.3048)
			(end 0.120396 0.3048)
			(stroke
				(width 0.1)
				(type default)
			)
			(layer "F.Fab")
		)
		(fp_line
			(start 0.67945 -0.3048)
			(end 0.67945 0.3048)
			(stroke
				(width 0.1)
				(type default)
			)
			(layer "F.Fab")
		)
		(fp_line
			(start 0.12065 -0.2794)
			(end 0.12065 -0.3048)
			(stroke
				(width 0.1)
				(type default)
			)
			(layer "F.Fab")
		)
		(fp_line
			(start 0.12065 -0.3048)
			(end 0.67945 -0.3048)
			(stroke
				(width 0.1)
				(type default)
			)
			(layer "F.Fab")
		)
		(fp_line
			(start 0.120396 0.3048)
			(end 0.120396 0.2794)
			(stroke
				(width 0.1)
				(type default)
			)
			(layer "F.Fab")
		)
		(fp_line
			(start 0.120396 0.2794)
			(end -0.12065 0.2794)
			(stroke
				(width 0.1)
				(type default)
			)
			(layer "F.Fab")
		)
		(fp_line
			(start -0.12065 0.3048)
			(end -0.67945 0.3048)
			(stroke
				(width 0.1)
				(type default)
			)
			(layer "F.Fab")
		)
		(fp_line
			(start -0.12065 0.2794)
			(end -0.12065 0.3048)
			(stroke
				(width 0.1)
				(type default)
			)
			(layer "F.Fab")
		)
		(fp_line
			(start -0.12065 -0.2794)
			(end 0.12065 -0.2794)
			(stroke
				(width 0.1)
				(type default)
			)
			(layer "F.Fab")
		)
		(fp_line
			(start -0.12065 -0.305054)
			(end -0.12065 -0.2794)
			(stroke
				(width 0.1)
				(type default)
			)
			(layer "F.Fab")
		)
		(fp_line
			(start -0.67945 0.3048)
			(end -0.67945 -0.305054)
			(stroke
				(width 0.1)
				(type default)
			)
			(layer "F.Fab")
		)
		(fp_line
			(start -0.67945 -0.305054)
			(end -0.12065 -0.305054)
			(stroke
				(width 0.1)
				(type default)
			)
			(layer "F.Fab")
		)
		(pad "1" smd circle
			(at -0.40005 0 180)
			(size 0 0)
			(layers "F.Cu" "F.Mask" "F.Paste")
			(net "P3V3_AUX")
		)
		(pad "2" smd circle
			(at 0.40005 0 180)
			(size 0 0)
			(layers "F.Cu" "F.Mask" "F.Paste")
			(net "GND")
		)
	)
)
